# S9S_MB_2U (Grand Teton) — schematic netlist excerpt (pin names and nets, part order shuffled) for the footprints in the layout excerpt that follows; sources: Cadence DE-HDL packaged netlist, KiCad conversion of 03242023_DA0F0TMBIJ0_F0T_Motherboard_J_brd_V01_OCP.brd

C2391  Q_CAP  1000PF 50V 5% EMPTY  pkg 0402  page 144 : A = PRSNT_CABLE_GPU_A3_ISO_N ; B = GND
R3290  Q_RES  1K 1% EMPTY  pkg 0402LF  page 166 : A = FM_P2E_SWA ; B = GND
PL21  Q_INDUCTOR  120NH/69A IND  pkg SMLF  page 293 : \1\ = SW_PVCCINFAON_CPU1_SW1 ; \2\ = PVCCINFAON_CPU1

(kicad_pcb
	(version 20260206)
	(generator "pcbnew")
	(generator_version "10.0")
	(general
		(thickness 1.6)
		(legacy_teardrops no)
	)
	(paper "A4")
	(title_block
		(title "03242023_DA0F0TMBIJ0_F0T_Motherboard_J_brd_V01_OCP.brd")
		(comment 1 "Grand Teton / footprints 1275-1277 of 6105")
	)
	(layers
		(0 "F.Cu" signal "TOP")
		(4 "In1.Cu" signal "GND")
		(6 "In2.Cu" signal "IN1")
		(8 "In3.Cu" signal "GND1")
		(10 "In4.Cu" signal "IN2")
		(12 "In5.Cu" signal "GND2")
		(14 "In6.Cu" signal "IN3")
		(16 "In7.Cu" signal "GND3")
		(18 "In8.Cu" signal "VCC")
		(20 "In9.Cu" signal "VCC1")
		(22 "In10.Cu" signal "GND4")
		(24 "In11.Cu" signal "IN4")
		(26 "In12.Cu" signal "GND5")
		(28 "In13.Cu" signal "IN5")
		(30 "In14.Cu" signal "GND6")
		(32 "In15.Cu" signal "IN6")
		(34 "In16.Cu" signal "GND7")
		(2 "B.Cu" signal "BOTTOM")
		(9 "F.Adhes" user "F.Adhesive")
		(11 "B.Adhes" user "B.Adhesive")
		(13 "F.Paste" user "Package Geometry/Pastemask Top")
		(15 "B.Paste" user "Package Geometry/Pastemask Bottom")
		(5 "F.SilkS" user "Ref Des/Silkscreen Top")
		(7 "B.SilkS" user "Ref Des/Silkscreen Bottom")
		(1 "F.Mask" user "Board Geometry/Soldermask Top")
		(3 "B.Mask" user "Board Geometry/Soldermask Bottom")
		(17 "Dwgs.User" user "User.Drawings")
		(19 "Cmts.User" user "User.Comments")
		(21 "Eco1.User" user "User.Eco1")
		(23 "Eco2.User" user "User.Eco2")
		(25 "Edge.Cuts" user "Board Geometry/Outline")
		(27 "Margin" user)
		(31 "F.CrtYd" user "Package Geometry/Place Bound Top")
		(29 "B.CrtYd" user "Package Geometry/Place Bound Bottom")
		(35 "F.Fab" user "Ref Des/Assembly Top")
		(33 "B.Fab" user "Ref Des/Assembly Bottom")
	)
	(footprint ""
		(layer "F.Cu")
		(at 365.2012 -414.7566)
		(property "Reference" "C2391"
			(at 0 0 0)
			(layer "F.SilkS")
			(hide yes)
			(effects
				(font
					(size 1.27 1.27)
				)
			)
		)
		(property "Value" ""
			(at 0 0 0)
			(layer "F.Fab")
			(effects
				(font
					(size 1.27 1.27)
				)
			)
		)
		(duplicate_pad_numbers_are_jumpers no)
		(fp_line
			(start -0.7874 -0.4064)
			(end 0.7874 -0.4064)
			(stroke
				(width 0.1524)
				(type default)
			)
			(layer "F.SilkS")
		)
		(fp_line
			(start -0.7874 0.4064)
			(end -0.7874 -0.4064)
			(stroke
				(width 0.1524)
				(type default)
			)
			(layer "F.SilkS")
		)
		(fp_line
			(start 0.7874 -0.4064)
			(end 0.7874 0.4064)
			(stroke
				(width 0.1524)
				(type default)
			)
			(layer "F.SilkS")
		)
		(fp_line
			(start 0.7874 0.4064)
			(end -0.7874 0.4064)
			(stroke
				(width 0.1524)
				(type default)
			)
			(layer "F.SilkS")
		)
		(fp_line
			(start -0.67945 -0.305054)
			(end -0.12065 -0.305054)
			(stroke
				(width 0.1)
				(type default)
			)
			(layer "F.Fab")
		)
		(fp_line
			(start -0.67945 0.3048)
			(end -0.67945 -0.305054)
			(stroke
				(width 0.1)
				(type default)
			)
			(layer "F.Fab")
		)
		(fp_line
			(start -0.12065 -0.305054)
			(end -0.12065 -0.2794)
			(stroke
				(width 0.1)
				(type default)
			)
			(layer "F.Fab")
		)
		(fp_line
			(start -0.12065 -0.2794)
			(end 0.12065 -0.2794)
			(stroke
				(width 0.1)
				(type default)
			)
			(layer "F.Fab")
		)
		(fp_line
			(start -0.12065 0.2794)
			(end -0.12065 0.3048)
			(stroke
				(width 0.1)
				(type default)
			)
			(layer "F.Fab")
		)
		(fp_line
			(start -0.12065 0.3048)
			(end -0.67945 0.3048)
			(stroke
				(width 0.1)
				(type default)
			)
			(layer "F.Fab")
		)
		(fp_line
			(start 0.120396 0.2794)
			(end -0.12065 0.2794)
			(stroke
				(width 0.1)
				(type default)
			)
			(layer "F.Fab")
		)
		(fp_line
			(start 0.120396 0.3048)
			(end 0.120396 0.2794)
			(stroke
				(width 0.1)
				(type default)
			)
			(layer "F.Fab")
		)
		(fp_line
			(start 0.12065 -0.3048)
			(end 0.67945 -0.3048)
			(stroke
				(width 0.1)
				(type default)
			)
			(layer "F.Fab")
		)
		(fp_line
			(start 0.12065 -0.2794)
			(end 0.12065 -0.3048)
			(stroke
				(width 0.1)
				(type default)
			)
			(layer "F.Fab")
		)
		(fp_line
			(start 0.67945 -0.3048)
			(end 0.67945 0.3048)
			(stroke
				(width 0.1)
				(type default)
			)
			(layer "F.Fab")
		)
		(fp_line
			(start 0.67945 0.3048)
			(end 0.120396 0.3048)
			(stroke
				(width 0.1)
				(type default)
			)
			(layer "F.Fab")
		)
		(pad "1" smd circle
			(at -0.40005 0)
			(size 0 0)
			(layers "F.Cu" "F.Mask" "F.Paste")
			(net "PRSNT_CABLE_GPU_A3_ISO_N")
		)
		(pad "2" smd circle
			(at 0.40005 0)
			(size 0 0)
			(layers "F.Cu" "F.Mask" "F.Paste")
			(net "GND")
		)
	)
	(footprint ""
		(layer "F.Cu")
		(at 15.436596 -389.151876 180)
		(property "Reference" "R3290"
			(at 0 0 180)
			(layer "F.SilkS")
			(hide yes)
			(effects
				(font
					(size 1.27 1.27)
				)
			)
		)
		(property "Value" ""
			(at 0 0 180)
			(layer "F.Fab")
			(effects
				(font
					(size 1.27 1.27)
				)
			)
		)
		(duplicate_pad_numbers_are_jumpers no)
		(fp_line
			(start 0.7874 0.4064)
			(end -0.7874 0.4064)
			(stroke
				(width 0.1524)
				(type default)
			)
			(layer "F.SilkS")
		)
		(fp_line
			(start 0.7874 -0.4064)
			(end 0.7874 0.4064)
			(stroke
				(width 0.1524)
				(type default)
			)
			(layer "F.SilkS")
		)
		(fp_line
			(start -0.7874 0.4064)
			(end -0.7874 -0.4064)
			(stroke
				(width 0.1524)
				(type default)
			)
			(layer "F.SilkS")
		)
		(fp_line
			(start -0.7874 -0.4064)
			(end 0.7874 -0.4064)
			(stroke
				(width 0.1524)
				(type default)
			)
			(layer "F.SilkS")
		)
		(fp_line
			(start 0.67945 0.3048)
			(end 0.120396 0.3048)
			(stroke
				(width 0.1)
				(type default)
			)
			(layer "F.Fab")
		)
		(fp_line
			(start 0.67945 -0.3048)
			(end 0.67945 0.3048)
			(stroke
				(width 0.1)
				(type default)
			)
			(layer "F.Fab")
		)
		(fp_line
			(start 0.12065 -0.2794)
			(end 0.12065 -0.3048)
			(stroke
				(width 0.1)
				(type default)
			)
			(layer "F.Fab")
		)
		(fp_line
			(start 0.12065 -0.3048)
			(end 0.67945 -0.3048)
			(stroke
				(width 0.1)
				(type default)
			)
			(layer "F.Fab")
		)
		(fp_line
			(start 0.120396 0.3048)
			(end 0.120396 0.2794)
			(stroke
				(width 0.1)
				(type default)
			)
			(layer "F.Fab")
		)
		(fp_line
			(start 0.120396 0.2794)
			(end -0.12065 0.2794)
			(stroke
				(width 0.1)
				(type default)
			)
			(layer "F.Fab")
		)
		(fp_line
			(start -0.12065 0.3048)
			(end -0.67945 0.3048)
			(stroke
				(width 0.1)
				(type default)
			)
			(layer "F.Fab")
		)
		(fp_line
			(start -0.12065 0.2794)
			(end -0.12065 0.3048)
			(stroke
				(width 0.1)
				(type default)
			)
			(layer "F.Fab")
		)
		(fp_line
			(start -0.12065 -0.2794)
			(end 0.12065 -0.2794)
			(stroke
				(width 0.1)
				(type default)
			)
			(layer "F.Fab")
		)
		(fp_line
			(start -0.12065 -0.305054)
			(end -0.12065 -0.2794)
			(stroke
				(width 0.1)
				(type default)
			)
			(layer "F.Fab")
		)
		(fp_line
			(start -0.67945 0.3048)
			(end -0.67945 -0.305054)
			(stroke
				(width 0.1)
				(type default)
			)
			(layer "F.Fab")
		)
		(fp_line
			(start -0.67945 -0.305054)
			(end -0.12065 -0.305054)
			(stroke
				(width 0.1)
				(type default)
			)
			(layer "F.Fab")
		)
		(pad "1" smd circle
			(at -0.40005 0 180)
			(size 0 0)
			(layers "F.Cu" "F.Mask" "F.Paste")
			(net "FM_P2E_SWA")
		)
		(pad "2" smd circle
			(at 0.40005 0 180)
			(size 0 0)
			(layers "F.Cu" "F.Mask" "F.Paste")
			(net "GND")
		)
	)
	(footprint ""
		(layer "F.Cu")
		(at 62.35446 -156.47797)
		(property "Reference" "PL21"
			(at -3.47726 -4.491228 0)
			(unlocked yes)
			(layer "F.SilkS")
			(effects
				(font
					(size 0.7874 0.5842)
					(thickness 0.1524)
				)
				(justify left)
			)
		)
		(property "Value" ""
			(at 0 0 0)
			(layer "F.Fab")
			(effects
				(font
					(size 1.27 1.27)
				)
			)
		)
		(duplicate_pad_numbers_are_jumpers no)
		(fp_line
			(start -3.24993 -3.24993)
			(end 3.24993 -3.24993)
			(stroke
				(width 0.1524)
				(type default)
			)
			(layer "F.SilkS")
		)
		(fp_line
			(start -3.24993 -2.2352)
			(end -3.24993 -3.24993)
			(stroke
				(width 0.1524)
				(type default)
			)
			(layer "F.SilkS")
		)
		(fp_line
			(start -3.24993 3.24993)
			(end -3.24993 2.2352)
			(stroke
				(width 0.1524)
				(type default)
			)
			(layer "F.SilkS")
		)
		(fp_line
			(start 3.24993 -3.24993)
			(end 3.24993 -2.2352)
			(stroke
				(width 0.1524)
				(type default)
			)
			(layer "F.SilkS")
		)
		(fp_line
			(start 3.24993 2.2352)
			(end 3.24993 3.24993)
			(stroke
				(width 0.1524)
				(type default)
			)
			(layer "F.SilkS")
		)
		(fp_line
			(start 3.24993 3.24993)
			(end -3.24993 3.24993)
			(stroke
				(width 0.1524)
				(type default)
			)
			(layer "F.SilkS")
		)
		(fp_line
			(start -3.24993 -3.24993)
			(end 3.24993 -3.24993)
			(stroke
				(width 0.1)
				(type default)
			)
			(layer "F.Fab")
		)
		(fp_line
			(start -3.24993 3.24993)
			(end -3.24993 -3.24993)
			(stroke
				(width 0.1)
				(type default)
			)
			(layer "F.Fab")
		)
		(fp_line
			(start 3.24993 -3.24993)
			(end 3.24993 3.24993)
			(stroke
				(width 0.1)
				(type default)
			)
			(layer "F.Fab")
		)
		(fp_line
			(start 3.24993 3.24993)
			(end -3.24993 3.24993)
			(stroke
				(width 0.1)
				(type default)
			)
			(layer "F.Fab")
		)
		(pad "1" smd rect
			(at -2.29997 0)
			(size 2.0066 4.2164)
			(layers "F.Cu" "F.Mask" "F.Paste")
			(net "SW_PVCCINFAON_CPU1_SW1")
		)
		(pad "2" smd rect
			(at 2.29997 0)
			(size 2.0066 4.2164)
			(layers "F.Cu" "F.Mask" "F.Paste")
			(net "PVCCINFAON_CPU1")
		)
	)
)
